# S9S_MB_2U (Grand Teton) — schematic netlist excerpt (pin names and nets, part order shuffled) for the footprints in the layout excerpt that follows; sources: Cadence DE-HDL packaged netlist, KiCad conversion of 03242023_DA0F0TMBIJ0_F0T_Motherboard_J_brd_V01_OCP.brd

PC547  Q_CAP  0.1UF 25V 10% EMPTY  pkg 0402  page 284 : A = PVCCIN_CPU1_CSPIN ; B = GND
C1233  Q_CAP  0.1UF 25V 10% X7R  pkg 0402  page 153 : A = P12V_OCP_SFF ; B = GND

(kicad_pcb
	(version 20260206)
	(generator "pcbnew")
	(generator_version "10.0")
	(general
		(thickness 1.6)
		(legacy_teardrops no)
	)
	(paper "A4")
	(title_block
		(title "03242023_DA0F0TMBIJ0_F0T_Motherboard_J_brd_V01_OCP.brd")
		(comment 1 "Grand Teton / footprints 871-872 of 6105")
	)
	(layers
		(0 "F.Cu" signal "TOP")
		(4 "In1.Cu" signal "GND")
		(6 "In2.Cu" signal "IN1")
		(8 "In3.Cu" signal "GND1")
		(10 "In4.Cu" signal "IN2")
		(12 "In5.Cu" signal "GND2")
		(14 "In6.Cu" signal "IN3")
		(16 "In7.Cu" signal "GND3")
		(18 "In8.Cu" signal "VCC")
		(20 "In9.Cu" signal "VCC1")
		(22 "In10.Cu" signal "GND4")
		(24 "In11.Cu" signal "IN4")
		(26 "In12.Cu" signal "GND5")
		(28 "In13.Cu" signal "IN5")
		(30 "In14.Cu" signal "GND6")
		(32 "In15.Cu" signal "IN6")
		(34 "In16.Cu" signal "GND7")
		(2 "B.Cu" signal "BOTTOM")
		(9 "F.Adhes" user "F.Adhesive")
		(11 "B.Adhes" user "B.Adhesive")
		(13 "F.Paste" user "Package Geometry/Pastemask Top")
		(15 "B.Paste" user "Package Geometry/Pastemask Bottom")
		(5 "F.SilkS" user "Ref Des/Silkscreen Top")
		(7 "B.SilkS" user "Ref Des/Silkscreen Bottom")
		(1 "F.Mask" user "Board Geometry/Soldermask Top")
		(3 "B.Mask" user "Board Geometry/Soldermask Bottom")
		(17 "Dwgs.User" user "User.Drawings")
		(19 "Cmts.User" user "User.Comments")
		(21 "Eco1.User" user "User.Eco1")
		(23 "Eco2.User" user "User.Eco2")
		(25 "Edge.Cuts" user "Board Geometry/Outline")
		(27 "Margin" user)
		(31 "F.CrtYd" user "Package Geometry/Place Bound Top")
		(29 "B.CrtYd" user "Package Geometry/Place Bound Bottom")
		(35 "F.Fab" user "Ref Des/Assembly Top")
		(33 "B.Fab" user "Ref Des/Assembly Bottom")
	)
	(footprint ""
		(layer "F.Cu")
		(at 114.706654 -359.94975)
		(property "Reference" "PC547"
			(at 0 0 0)
			(layer "F.SilkS")
			(hide yes)
			(effects
				(font
					(size 1.27 1.27)
				)
			)
		)
		(property "Value" ""
			(at 0 0 0)
			(layer "F.Fab")
			(effects
				(font
					(size 1.27 1.27)
				)
			)
		)
		(duplicate_pad_numbers_are_jumpers no)
		(fp_line
			(start -0.7874 -0.4064)
			(end 0.7874 -0.4064)
			(stroke
				(width 0.1524)
				(type default)
			)
			(layer "F.SilkS")
		)
		(fp_line
			(start -0.7874 0.4064)
			(end -0.7874 -0.4064)
			(stroke
				(width 0.1524)
				(type default)
			)
			(layer "F.SilkS")
		)
		(fp_line
			(start 0.7874 -0.4064)
			(end 0.7874 0.4064)
			(stroke
				(width 0.1524)
				(type default)
			)
			(layer "F.SilkS")
		)
		(fp_line
			(start 0.7874 0.4064)
			(end -0.7874 0.4064)
			(stroke
				(width 0.1524)
				(type default)
			)
			(layer "F.SilkS")
		)
		(fp_line
			(start -0.67945 -0.305054)
			(end -0.12065 -0.305054)
			(stroke
				(width 0.1)
				(type default)
			)
			(layer "F.Fab")
		)
		(fp_line
			(start -0.67945 0.3048)
			(end -0.67945 -0.305054)
			(stroke
				(width 0.1)
				(type default)
			)
			(layer "F.Fab")
		)
		(fp_line
			(start -0.12065 -0.305054)
			(end -0.12065 -0.2794)
			(stroke
				(width 0.1)
				(type default)
			)
			(layer "F.Fab")
		)
		(fp_line
			(start -0.12065 -0.2794)
			(end 0.12065 -0.2794)
			(stroke
				(width 0.1)
				(type default)
			)
			(layer "F.Fab")
		)
		(fp_line
			(start -0.12065 0.2794)
			(end -0.12065 0.3048)
			(stroke
				(width 0.1)
				(type default)
			)
			(layer "F.Fab")
		)
		(fp_line
			(start -0.12065 0.3048)
			(end -0.67945 0.3048)
			(stroke
				(width 0.1)
				(type default)
			)
			(layer "F.Fab")
		)
		(fp_line
			(start 0.120396 0.2794)
			(end -0.12065 0.2794)
			(stroke
				(width 0.1)
				(type default)
			)
			(layer "F.Fab")
		)
		(fp_line
			(start 0.120396 0.3048)
			(end 0.120396 0.2794)
			(stroke
				(width 0.1)
				(type default)
			)
			(layer "F.Fab")
		)
		(fp_line
			(start 0.12065 -0.3048)
			(end 0.67945 -0.3048)
			(stroke
				(width 0.1)
				(type default)
			)
			(layer "F.Fab")
		)
		(fp_line
			(start 0.12065 -0.2794)
			(end 0.12065 -0.3048)
			(stroke
				(width 0.1)
				(type default)
			)
			(layer "F.Fab")
		)
		(fp_line
			(start 0.67945 -0.3048)
			(end 0.67945 0.3048)
			(stroke
				(width 0.1)
				(type default)
			)
			(layer "F.Fab")
		)
		(fp_line
			(start 0.67945 0.3048)
			(end 0.120396 0.3048)
			(stroke
				(width 0.1)
				(type default)
			)
			(layer "F.Fab")
		)
		(pad "1" smd circle
			(at -0.40005 0)
			(size 0 0)
			(layers "F.Cu" "F.Mask" "F.Paste")
			(net "PVCCIN_CPU1_CSPIN")
		)
		(pad "2" smd circle
			(at 0.40005 0)
			(size 0 0)
			(layers "F.Cu" "F.Mask" "F.Paste")
			(net "GND")
		)
	)
	(footprint ""
		(layer "F.Cu")
		(at 440.383676 -15.656306 180)
		(property "Reference" "C1233"
			(at 0 0 180)
			(layer "F.SilkS")
			(hide yes)
			(effects
				(font
					(size 1.27 1.27)
				)
			)
		)
		(property "Value" ""
			(at 0 0 180)
			(layer "F.Fab")
			(effects
				(font
					(size 1.27 1.27)
				)
			)
		)
		(duplicate_pad_numbers_are_jumpers no)
		(fp_line
			(start 0.7874 0.4064)
			(end -0.7874 0.4064)
			(stroke
				(width 0.1524)
				(type default)
			)
			(layer "F.SilkS")
		)
		(fp_line
			(start 0.7874 -0.4064)
			(end 0.7874 0.4064)
			(stroke
				(width 0.1524)
				(type default)
			)
			(layer "F.SilkS")
		)
		(fp_line
			(start -0.7874 0.4064)
			(end -0.7874 -0.4064)
			(stroke
				(width 0.1524)
				(type default)
			)
			(layer "F.SilkS")
		)
		(fp_line
			(start -0.7874 -0.4064)
			(end 0.7874 -0.4064)
			(stroke
				(width 0.1524)
				(type default)
			)
			(layer "F.SilkS")
		)
		(fp_line
			(start 0.67945 0.3048)
			(end 0.120396 0.3048)
			(stroke
				(width 0.1)
				(type default)
			)
			(layer "F.Fab")
		)
		(fp_line
			(start 0.67945 -0.3048)
			(end 0.67945 0.3048)
			(stroke
				(width 0.1)
				(type default)
			)
			(layer "F.Fab")
		)
		(fp_line
			(start 0.12065 -0.2794)
			(end 0.12065 -0.3048)
			(stroke
				(width 0.1)
				(type default)
			)
			(layer "F.Fab")
		)
		(fp_line
			(start 0.12065 -0.3048)
			(end 0.67945 -0.3048)
			(stroke
				(width 0.1)
				(type default)
			)
			(layer "F.Fab")
		)
		(fp_line
			(start 0.120396 0.3048)
			(end 0.120396 0.2794)
			(stroke
				(width 0.1)
				(type default)
			)
			(layer "F.Fab")
		)
		(fp_line
			(start 0.120396 0.2794)
			(end -0.12065 0.2794)
			(stroke
				(width 0.1)
				(type default)
			)
			(layer "F.Fab")
		)
		(fp_line
			(start -0.12065 0.3048)
			(end -0.67945 0.3048)
			(stroke
				(width 0.1)
				(type default)
			)
			(layer "F.Fab")
		)
		(fp_line
			(start -0.12065 0.2794)
			(end -0.12065 0.3048)
			(stroke
				(width 0.1)
				(type default)
			)
			(layer "F.Fab")
		)
		(fp_line
			(start -0.12065 -0.2794)
			(end 0.12065 -0.2794)
			(stroke
				(width 0.1)
				(type default)
			)
			(layer "F.Fab")
		)
		(fp_line
			(start -0.12065 -0.305054)
			(end -0.12065 -0.2794)
			(stroke
				(width 0.1)
				(type default)
			)
			(layer "F.Fab")
		)
		(fp_line
			(start -0.67945 0.3048)
			(end -0.67945 -0.305054)
			(stroke
				(width 0.1)
				(type default)
			)
			(layer "F.Fab")
		)
		(fp_line
			(start -0.67945 -0.305054)
			(end -0.12065 -0.305054)
			(stroke
				(width 0.1)
				(type default)
			)
			(layer "F.Fab")
		)
		(pad "1" smd circle
			(at -0.40005 0 180)
			(size 0 0)
			(layers "F.Cu" "F.Mask" "F.Paste")
			(net "P12V_OCP_SFF")
		)
		(pad "2" smd circle
			(at 0.40005 0 180)
			(size 0 0)
			(layers "F.Cu" "F.Mask" "F.Paste")
			(net "GND")
		)
	)
)
